# TIMECARD (Time Appliance Project (Time Card)) — schematic netlist excerpt (pin names and nets, part order shuffled) for the footprints in the layout excerpt that follows; sources: Cadence DE-HDL packaged netlist, KiCad conversion of R4006-B0001-02_R01.brd

R291  RESISTOR  4.7KOHM 1%  pkg SMC_0402R_H016  page 20 : \1\ = XP3R3V_FPGA ; \2\ = R_BNO080_RST_N
R453  RESISTOR  1KOHM 1%  pkg SMC_0402R_H016  page 24 : \1\ = UNNAMED_524_POWERMOS3PNCHV1_I44 ; \2\ = SG

(kicad_pcb
	(version 20260206)
	(generator "pcbnew")
	(generator_version "10.0")
	(general
		(thickness 1.6)
		(legacy_teardrops no)
	)
	(paper "A4")
	(title_block
		(title "timecard-production-celestica-r4006 — R4006-B0001-02_R01.brd")
		(comment 1 "Time Appliance Project (Time Card) / footprints 513-514 of 1113")
	)
	(layers
		(0 "F.Cu" signal "TOP")
		(4 "In1.Cu" signal "L02_GND1")
		(6 "In2.Cu" signal "L03_SIG1")
		(8 "In3.Cu" signal "L04_GND2")
		(10 "In4.Cu" signal "L05_VCC1")
		(12 "In5.Cu" signal "L06_VCC2")
		(14 "In6.Cu" signal "L07_GND3")
		(16 "In7.Cu" signal "L08_SIG2")
		(18 "In8.Cu" signal "L09_GND4")
		(2 "B.Cu" signal "BOTTOM")
		(9 "F.Adhes" user "F.Adhesive")
		(11 "B.Adhes" user "B.Adhesive")
		(13 "F.Paste" user "Package Geometry/Pastemask Top")
		(15 "B.Paste" user "Package Geometry/Pastemask Bottom")
		(5 "F.SilkS" user "Ref Des/Silkscreen Top")
		(7 "B.SilkS" user "Ref Des/Silkscreen Bottom")
		(1 "F.Mask" user "Board Geometry/Soldermask Top")
		(3 "B.Mask" user "Board Geometry/Soldermask Bottom")
		(17 "Dwgs.User" user "User.Drawings")
		(19 "Cmts.User" user "User.Comments")
		(21 "Eco1.User" user "User.Eco1")
		(23 "Eco2.User" user "User.Eco2")
		(25 "Edge.Cuts" user "Board Geometry/Outline")
		(27 "Margin" user)
		(31 "F.CrtYd" user "Package Geometry/Place Bound Top")
		(29 "B.CrtYd" user "Package Geometry/Place Bound Bottom")
		(35 "F.Fab" user "Ref Des/Assembly Top")
		(33 "B.Fab" user "Ref Des/Assembly Bottom")
	)
	(footprint ""
		(layer "F.Cu")
		(at 111.887 -95.123)
		(property "Reference" "R453"
			(at 3.175 0.03937 0)
			(unlocked yes)
			(layer "F.SilkS")
			(effects
				(font
					(size 0.7874 0.5842)
					(thickness 0.1524)
				)
			)
		)
		(property "Value" "VAL*"
			(at 0.02032 2.13233 0)
			(unlocked yes)
			(layer "F.Fab")
			(hide yes)
			(effects
				(font
					(size 0.7874 0.5842)
					(thickness 0.1524)
				)
			)
		)
		(property "Tolerance" "TOL*"
			(at 0.044704 3.05435 0)
			(unlocked yes)
			(layer "Cmts.User")
			(hide yes)
			(effects
				(font
					(size 0.7874 0.5842)
					(thickness 0.1524)
				)
			)
		)
		(property "User Part Number" "PARTNUM*"
			(at 0.02032 4.024884 0)
			(unlocked yes)
			(layer "Cmts.User")
			(hide yes)
			(effects
				(font
					(size 0.7874 0.5842)
					(thickness 0.1524)
				)
			)
		)
		(property "Device Type" "RESISTOR-G155-11001-01,1KOHM,1%"
			(at 0.008382 1.210564 0)
			(unlocked yes)
			(layer "F.Fab")
			(hide yes)
			(effects
				(font
					(size 0.7874 0.5842)
					(thickness 0.1524)
				)
			)
		)
		(duplicate_pad_numbers_are_jumpers no)
		(fp_line
			(start -1.143 -0.5588)
			(end -1.143 0.5588)
			(stroke
				(width 0.1)
				(type default)
			)
			(layer "F.SilkS")
		)
		(fp_line
			(start -1.143 0.5588)
			(end 1.143 0.5588)
			(stroke
				(width 0.1)
				(type default)
			)
			(layer "F.SilkS")
		)
		(fp_line
			(start 1.143 -0.5588)
			(end -1.143 -0.5588)
			(stroke
				(width 0.1)
				(type default)
			)
			(layer "F.SilkS")
		)
		(fp_line
			(start 1.143 0.5588)
			(end 1.143 -0.5588)
			(stroke
				(width 0.1)
				(type default)
			)
			(layer "F.SilkS")
		)
		(fp_poly
			(pts
				(xy -1.143 0.5588) (xy 1.143 0.5588) (xy 1.143 -0.5588) (xy -1.143 -0.5588)
			)
			(stroke
				(width 0)
				(type default)
			)
			(fill no)
			(layer "F.CrtYd")
		)
		(fp_line
			(start -0.508 -0.3048)
			(end -0.508 0.3048)
			(stroke
				(width 0.1)
				(type default)
			)
			(layer "F.Fab")
		)
		(fp_line
			(start -0.508 0.3048)
			(end 0.508 0.3048)
			(stroke
				(width 0.1)
				(type default)
			)
			(layer "F.Fab")
		)
		(fp_line
			(start 0.508 -0.3048)
			(end -0.508 -0.3048)
			(stroke
				(width 0.1)
				(type default)
			)
			(layer "F.Fab")
		)
		(fp_line
			(start 0.508 0.3048)
			(end 0.508 -0.3048)
			(stroke
				(width 0.1)
				(type default)
			)
			(layer "F.Fab")
		)
		(pad "1" smd rect
			(at -0.5334 0)
			(size 0.7112 0.6096)
			(layers "F.Cu" "F.Mask" "F.Paste")
			(net "UNNAMED_524_POWERMOS3PNCHV1_I44")
		)
		(pad "2" smd rect
			(at 0.5334 0)
			(size 0.7112 0.6096)
			(layers "F.Cu" "F.Mask" "F.Paste")
			(net "SG")
		)
		(zone
			(layer "F.Cu")
			(hatch none 0.5)
			(connect_pads
				(clearance 0)
			)
			(min_thickness 0.25)
			(keepout
				(tracks not_allowed)
				(vias allowed)
				(pads allowed)
				(copperpour not_allowed)
				(footprints allowed)
			)
			(placement
				(enabled no)
				(sheetname "")
			)
			(fill
				(thermal_gap 0.5)
				(thermal_bridge_width 0.5)
				(island_removal_mode 0)
			)
			(polygon
				(pts
					(xy 111.8108 -94.8182) (xy 111.9632 -94.8182) (xy 111.9632 -95.4278) (xy 111.8108 -95.4278)
				)
			)
		)
		(zone
			(layer "F.Cu")
			(hatch none 0.5)
			(connect_pads
				(clearance 0)
			)
			(min_thickness 0.25)
			(keepout
				(tracks allowed)
				(vias not_allowed)
				(pads allowed)
				(copperpour not_allowed)
				(footprints allowed)
			)
			(placement
				(enabled no)
				(sheetname "")
			)
			(fill
				(thermal_gap 0.5)
				(thermal_bridge_width 0.5)
				(island_removal_mode 0)
			)
			(polygon
				(pts
					(xy 111.8108 -94.8182) (xy 111.9632 -94.8182) (xy 111.9632 -95.4278) (xy 111.8108 -95.4278)
				)
			)
		)
	)
	(footprint ""
		(layer "F.Cu")
		(at 80.772 -60.6806)
		(property "Reference" "R291"
			(at -10.287 -19.51863 0)
			(unlocked yes)
			(layer "F.SilkS")
			(effects
				(font
					(size 0.7874 0.5842)
					(thickness 0.1524)
				)
			)
		)
		(property "Value" "VAL*"
			(at 0.02032 2.13233 0)
			(unlocked yes)
			(layer "F.Fab")
			(hide yes)
			(effects
				(font
					(size 0.7874 0.5842)
					(thickness 0.1524)
				)
			)
		)
		(property "Tolerance" "TOL*"
			(at 0.044704 3.05435 0)
			(unlocked yes)
			(layer "Cmts.User")
			(hide yes)
			(effects
				(font
					(size 0.7874 0.5842)
					(thickness 0.1524)
				)
			)
		)
		(property "User Part Number" "PARTNUM*"
			(at 0.02032 4.024884 0)
			(unlocked yes)
			(layer "Cmts.User")
			(hide yes)
			(effects
				(font
					(size 0.7874 0.5842)
					(thickness 0.1524)
				)
			)
		)
		(property "Device Type" "RESISTOR-G155-14701-01,4.7KOHMA"
			(at 0.008382 1.210564 0)
			(unlocked yes)
			(layer "F.Fab")
			(hide yes)
			(effects
				(font
					(size 0.7874 0.5842)
					(thickness 0.1524)
				)
			)
		)
		(duplicate_pad_numbers_are_jumpers no)
		(fp_line
			(start -1.143 -0.5588)
			(end -1.143 0.5588)
			(stroke
				(width 0.1)
				(type default)
			)
			(layer "F.SilkS")
		)
		(fp_line
			(start -1.143 0.5588)
			(end 1.143 0.5588)
			(stroke
				(width 0.1)
				(type default)
			)
			(layer "F.SilkS")
		)
		(fp_line
			(start 1.143 -0.5588)
			(end -1.143 -0.5588)
			(stroke
				(width 0.1)
				(type default)
			)
			(layer "F.SilkS")
		)
		(fp_line
			(start 1.143 0.5588)
			(end 1.143 -0.5588)
			(stroke
				(width 0.1)
				(type default)
			)
			(layer "F.SilkS")
		)
		(fp_rect
			(start -1.143 0.5588)
			(end 1.143 -0.5588)
			(stroke
				(width 0)
				(type default)
			)
			(fill no)
			(layer "F.CrtYd")
		)
		(fp_line
			(start -0.508 -0.3048)
			(end -0.508 0.3048)
			(stroke
				(width 0.1)
				(type default)
			)
			(layer "F.Fab")
		)
		(fp_line
			(start -0.508 0.3048)
			(end 0.508 0.3048)
			(stroke
				(width 0.1)
				(type default)
			)
			(layer "F.Fab")
		)
		(fp_line
			(start 0.508 -0.3048)
			(end -0.508 -0.3048)
			(stroke
				(width 0.1)
				(type default)
			)
			(layer "F.Fab")
		)
		(fp_line
			(start 0.508 0.3048)
			(end 0.508 -0.3048)
			(stroke
				(width 0.1)
				(type default)
			)
			(layer "F.Fab")
		)
		(pad "1" smd rect
			(at -0.5334 0)
			(size 0.7112 0.6096)
			(layers "F.Cu" "F.Mask" "F.Paste")
			(net "XP3R3V_FPGA")
		)
		(pad "2" smd rect
			(at 0.5334 0)
			(size 0.7112 0.6096)
			(layers "F.Cu" "F.Mask" "F.Paste")
			(net "R_BNO080_RST_N")
		)
		(zone
			(layer "F.Cu")
			(hatch none 0.5)
			(connect_pads
				(clearance 0)
			)
			(min_thickness 0.25)
			(keepout
				(tracks allowed)
				(vias not_allowed)
				(pads allowed)
				(copperpour not_allowed)
				(footprints allowed)
			)
			(placement
				(enabled no)
				(sheetname "")
			)
			(fill
				(thermal_gap 0.5)
				(thermal_bridge_width 0.5)
				(island_removal_mode 0)
			)
			(polygon
				(pts
					(xy 80.6958 -60.3758) (xy 80.8482 -60.3758) (xy 80.8482 -60.9854) (xy 80.6958 -60.9854)
				)
			)
		)
	)
)
